(kicad_pcb
	(version 20260206)
	(generator "pcbnew")
	(generator_version "10.0")
	(general
		(thickness 1.6)
		(legacy_teardrops no)
	)
	(paper "A4")
	(title_block
		(title "03242023_DA0F0TMBIJ0_F0T_Motherboard_J_brd_V01_OCP.brd")
		(comment 1 "Grand Teton / footprints 4490-4494 of 6105")
	)
	(layers
		(0 "F.Cu" signal "TOP")
		(4 "In1.Cu" signal "GND")
		(6 "In2.Cu" signal "IN1")
		(8 "In3.Cu" signal "GND1")
		(10 "In4.Cu" signal "IN2")
		(12 "In5.Cu" signal "GND2")
		(14 "In6.Cu" signal "IN3")
		(16 "In7.Cu" signal "GND3")
		(18 "In8.Cu" signal "VCC")
		(20 "In9.Cu" signal "VCC1")
		(22 "In10.Cu" signal "GND4")
		(24 "In11.Cu" signal "IN4")
		(26 "In12.Cu" signal "GND5")
		(28 "In13.Cu" signal "IN5")
		(30 "In14.Cu" signal "GND6")
		(32 "In15.Cu" signal "IN6")
		(34 "In16.Cu" signal "GND7")
		(2 "B.Cu" signal "BOTTOM")
		(9 "F.Adhes" user "F.Adhesive")
		(11 "B.Adhes" user "B.Adhesive")
		(13 "F.Paste" user "Package Geometry/Pastemask Top")
		(15 "B.Paste" user "Package Geometry/Pastemask Bottom")
		(5 "F.SilkS" user "Ref Des/Silkscreen Top")
		(7 "B.SilkS" user "Ref Des/Silkscreen Bottom")
		(1 "F.Mask" user "Board Geometry/Soldermask Top")
		(3 "B.Mask" user "Board Geometry/Soldermask Bottom")
		(17 "Dwgs.User" user "User.Drawings")
		(19 "Cmts.User" user "User.Comments")
		(21 "Eco1.User" user "User.Eco1")
		(23 "Eco2.User" user "User.Eco2")
		(25 "Edge.Cuts" user "Board Geometry/Outline")
		(27 "Margin" user)
		(31 "F.CrtYd" user "Package Geometry/Place Bound Top")
		(29 "B.CrtYd" user "Package Geometry/Place Bound Bottom")
		(35 "F.Fab" user "Ref Des/Assembly Top")
		(33 "B.Fab" user "Ref Des/Assembly Bottom")
	)
	(footprint ""
		(layer "B.Cu")
		(at 183.885078 -18.710148 90)
		(property "Reference" "R3238"
			(at 0 0 90)
			(layer "B.SilkS")
			(hide yes)
			(effects
				(font
					(size 1.27 1.27)
				)
				(justify mirror)
			)
		)
		(property "Value" ""
			(at 0 0 90)
			(layer "B.Fab")
			(effects
				(font
					(size 1.27 1.27)
				)
				(justify mirror)
			)
		)
		(duplicate_pad_numbers_are_jumpers no)
		(fp_line
			(start 0.7874 -0.4064)
			(end -0.7874 -0.4064)
			(stroke
				(width 0.1524)
				(type default)
			)
			(layer "B.SilkS")
		)
		(fp_line
			(start -0.7874 -0.4064)
			(end -0.7874 0.4064)
			(stroke
				(width 0.1524)
				(type default)
			)
			(layer "B.SilkS")
		)
		(fp_line
			(start 0.7874 0.4064)
			(end 0.7874 -0.4064)
			(stroke
				(width 0.1524)
				(type default)
			)
			(layer "B.SilkS")
		)
		(fp_line
			(start -0.7874 0.4064)
			(end 0.7874 0.4064)
			(stroke
				(width 0.1524)
				(type default)
			)
			(layer "B.SilkS")
		)
		(fp_line
			(start 0.67945 -0.305054)
			(end 0.12065 -0.305054)
			(stroke
				(width 0.1)
				(type default)
			)
			(layer "B.Fab")
		)
		(fp_line
			(start 0.12065 -0.305054)
			(end 0.12065 -0.2794)
			(stroke
				(width 0.1)
				(type default)
			)
			(layer "B.Fab")
		)
		(fp_line
			(start -0.12065 -0.3048)
			(end -0.67945 -0.3048)
			(stroke
				(width 0.1)
				(type default)
			)
			(layer "B.Fab")
		)
		(fp_line
			(start -0.67945 -0.3048)
			(end -0.67945 0.3048)
			(stroke
				(width 0.1)
				(type default)
			)
			(layer "B.Fab")
		)
		(fp_line
			(start 0.12065 -0.2794)
			(end -0.12065 -0.2794)
			(stroke
				(width 0.1)
				(type default)
			)
			(layer "B.Fab")
		)
		(fp_line
			(start -0.12065 -0.2794)
			(end -0.12065 -0.3048)
			(stroke
				(width 0.1)
				(type default)
			)
			(layer "B.Fab")
		)
		(fp_line
			(start 0.12065 0.2794)
			(end 0.12065 0.3048)
			(stroke
				(width 0.1)
				(type default)
			)
			(layer "B.Fab")
		)
		(fp_line
			(start -0.120396 0.2794)
			(end 0.12065 0.2794)
			(stroke
				(width 0.1)
				(type default)
			)
			(layer "B.Fab")
		)
		(fp_line
			(start 0.67945 0.3048)
			(end 0.67945 -0.305054)
			(stroke
				(width 0.1)
				(type default)
			)
			(layer "B.Fab")
		)
		(fp_line
			(start 0.12065 0.3048)
			(end 0.67945 0.3048)
			(stroke
				(width 0.1)
				(type default)
			)
			(layer "B.Fab")
		)
		(fp_line
			(start -0.120396 0.3048)
			(end -0.120396 0.2794)
			(stroke
				(width 0.1)
				(type default)
			)
			(layer "B.Fab")
		)
		(fp_line
			(start -0.67945 0.3048)
			(end -0.120396 0.3048)
			(stroke
				(width 0.1)
				(type default)
			)
			(layer "B.Fab")
		)
		(pad "1" smd circle
			(at 0.40005 0 270)
			(size 0 0)
			(layers "B.Cu" "B.Mask" "B.Paste")
			(net "SMB_OCP_SFF_3V3AUX_SCL")
		)
		(pad "2" smd circle
			(at -0.40005 0 270)
			(size 0 0)
			(layers "B.Cu" "B.Mask" "B.Paste")
			(net "SMB_OCP_SFF_3V3AUX_SCL_R0")
		)
	)
	(footprint ""
		(layer "B.Cu")
		(at 174.155608 -121.375424 -90)
		(property "Reference" "C1896"
			(at 0 0 90)
			(layer "B.SilkS")
			(hide yes)
			(effects
				(font
					(size 1.27 1.27)
				)
				(justify mirror)
			)
		)
		(property "Value" ""
			(at 0 0 90)
			(layer "B.Fab")
			(effects
				(font
					(size 1.27 1.27)
				)
				(justify mirror)
			)
		)
		(duplicate_pad_numbers_are_jumpers no)
		(fp_line
			(start -0.69215 0.2921)
			(end 0.69215 0.2921)
			(stroke
				(width 0.1524)
				(type default)
			)
			(layer "B.SilkS")
		)
		(fp_line
			(start 0.69215 0.2921)
			(end 0.69215 -0.2921)
			(stroke
				(width 0.1524)
				(type default)
			)
			(layer "B.SilkS")
		)
		(fp_line
			(start -0.69215 -0.2921)
			(end -0.69215 0.2921)
			(stroke
				(width 0.1524)
				(type default)
			)
			(layer "B.SilkS")
		)
		(fp_line
			(start 0.69215 -0.2921)
			(end -0.69215 -0.2921)
			(stroke
				(width 0.1524)
				(type default)
			)
			(layer "B.SilkS")
		)
		(fp_line
			(start -0.51435 0.2794)
			(end 0.51435 0.2794)
			(stroke
				(width 0.1)
				(type default)
			)
			(layer "B.Fab")
		)
		(fp_line
			(start 0.51435 0.2794)
			(end 0.51435 -0.2794)
			(stroke
				(width 0.1)
				(type default)
			)
			(layer "B.Fab")
		)
		(fp_line
			(start -0.51435 -0.2794)
			(end -0.51435 0.2794)
			(stroke
				(width 0.1)
				(type default)
			)
			(layer "B.Fab")
		)
		(fp_line
			(start 0.51435 -0.2794)
			(end -0.51435 -0.2794)
			(stroke
				(width 0.1)
				(type default)
			)
			(layer "B.Fab")
		)
		(pad "1" smd circle
			(at 0.40005 0 90)
			(size 0 0)
			(layers "B.Cu" "B.Mask" "B.Paste")
			(net "P3V3_AUX_FPGA_VCCIO1")
		)
		(pad "2" smd circle
			(at -0.40005 0 90)
			(size 0 0)
			(layers "B.Cu" "B.Mask" "B.Paste")
			(net "GND")
		)
		(zone
			(layer "B.Cu")
			(hatch none 0.5)
			(connect_pads
				(clearance 0)
			)
			(min_thickness 0.25)
			(keepout
				(tracks not_allowed)
				(vias allowed)
				(pads allowed)
				(copperpour not_allowed)
				(footprints allowed)
			)
			(placement
				(enabled no)
				(sheetname "")
			)
			(fill
				(thermal_gap 0.5)
				(thermal_bridge_width 0.5)
				(island_removal_mode 0)
			)
			(polygon
				(pts
					(xy 174.067978 -121.184924) (xy 174.009812 -121.276364) (xy 174.009812 -121.475754) (xy 174.067978 -121.565924)
					(xy 174.243238 -121.565924) (xy 174.301658 -121.475754) (xy 174.301658 -121.276364) (xy 174.243492 -121.184924)
				)
			)
		)
	)
	(footprint ""
		(layer "B.Cu")
		(at 36.956492 -132.783834 180)
		(property "Reference" "C2453"
			(at 0 0 0)
			(layer "B.SilkS")
			(hide yes)
			(effects
				(font
					(size 1.27 1.27)
				)
				(justify mirror)
			)
		)
		(property "Value" ""
			(at 0 0 0)
			(layer "B.Fab")
			(effects
				(font
					(size 1.27 1.27)
				)
				(justify mirror)
			)
		)
		(duplicate_pad_numbers_are_jumpers no)
		(fp_line
			(start 0.7874 0.4064)
			(end 0.7874 -0.4064)
			(stroke
				(width 0.1524)
				(type default)
			)
			(layer "B.SilkS")
		)
		(fp_line
			(start 0.7874 -0.4064)
			(end -0.7874 -0.4064)
			(stroke
				(width 0.1524)
				(type default)
			)
			(layer "B.SilkS")
		)
		(fp_line
			(start -0.7874 0.4064)
			(end 0.7874 0.4064)
			(stroke
				(width 0.1524)
				(type default)
			)
			(layer "B.SilkS")
		)
		(fp_line
			(start -0.7874 -0.4064)
			(end -0.7874 0.4064)
			(stroke
				(width 0.1524)
				(type default)
			)
			(layer "B.SilkS")
		)
		(fp_line
			(start 0.67945 0.3048)
			(end 0.67945 -0.305054)
			(stroke
				(width 0.1)
				(type default)
			)
			(layer "B.Fab")
		)
		(fp_line
			(start 0.67945 -0.305054)
			(end 0.12065 -0.305054)
			(stroke
				(width 0.1)
				(type default)
			)
			(layer "B.Fab")
		)
		(fp_line
			(start 0.12065 0.3048)
			(end 0.67945 0.3048)
			(stroke
				(width 0.1)
				(type default)
			)
			(layer "B.Fab")
		)
		(fp_line
			(start 0.12065 0.2794)
			(end 0.12065 0.3048)
			(stroke
				(width 0.1)
				(type default)
			)
			(layer "B.Fab")
		)
		(fp_line
			(start 0.12065 -0.2794)
			(end -0.12065 -0.2794)
			(stroke
				(width 0.1)
				(type default)
			)
			(layer "B.Fab")
		)
		(fp_line
			(start 0.12065 -0.305054)
			(end 0.12065 -0.2794)
			(stroke
				(width 0.1)
				(type default)
			)
			(layer "B.Fab")
		)
		(fp_line
			(start -0.120396 0.3048)
			(end -0.120396 0.2794)
			(stroke
				(width 0.1)
				(type default)
			)
			(layer "B.Fab")
		)
		(fp_line
			(start -0.120396 0.2794)
			(end 0.12065 0.2794)
			(stroke
				(width 0.1)
				(type default)
			)
			(layer "B.Fab")
		)
		(fp_line
			(start -0.12065 -0.2794)
			(end -0.12065 -0.3048)
			(stroke
				(width 0.1)
				(type default)
			)
			(layer "B.Fab")
		)
		(fp_line
			(start -0.12065 -0.3048)
			(end -0.67945 -0.3048)
			(stroke
				(width 0.1)
				(type default)
			)
			(layer "B.Fab")
		)
		(fp_line
			(start -0.67945 0.3048)
			(end -0.120396 0.3048)
			(stroke
				(width 0.1)
				(type default)
			)
			(layer "B.Fab")
		)
		(fp_line
			(start -0.67945 -0.3048)
			(end -0.67945 0.3048)
			(stroke
				(width 0.1)
				(type default)
			)
			(layer "B.Fab")
		)
		(pad "1" smd circle
			(at 0.40005 0)
			(size 0 0)
			(layers "B.Cu" "B.Mask" "B.Paste")
			(net "PWRGD_PVCCFA_EHV_CPU1_R")
		)
		(pad "2" smd circle
			(at -0.40005 0)
			(size 0 0)
			(layers "B.Cu" "B.Mask" "B.Paste")
			(net "GND")
		)
	)
	(footprint ""
		(layer "B.Cu")
		(at 208.127854 -318.641476 90)
		(property "Reference" "R908"
			(at 0 0 90)
			(layer "B.SilkS")
			(hide yes)
			(effects
				(font
					(size 1.27 1.27)
				)
				(justify mirror)
			)
		)
		(property "Value" ""
			(at 0 0 90)
			(layer "B.Fab")
			(effects
				(font
					(size 1.27 1.27)
				)
				(justify mirror)
			)
		)
		(duplicate_pad_numbers_are_jumpers no)
		(fp_line
			(start 0.7874 -0.4064)
			(end -0.7874 -0.4064)
			(stroke
				(width 0.1524)
				(type default)
			)
			(layer "B.SilkS")
		)
		(fp_line
			(start -0.7874 -0.4064)
			(end -0.7874 0.4064)
			(stroke
				(width 0.1524)
				(type default)
			)
			(layer "B.SilkS")
		)
		(fp_line
			(start 0.7874 0.4064)
			(end 0.7874 -0.4064)
			(stroke
				(width 0.1524)
				(type default)
			)
			(layer "B.SilkS")
		)
		(fp_line
			(start -0.7874 0.4064)
			(end 0.7874 0.4064)
			(stroke
				(width 0.1524)
				(type default)
			)
			(layer "B.SilkS")
		)
		(fp_line
			(start 0.67945 -0.305054)
			(end 0.12065 -0.305054)
			(stroke
				(width 0.1)
				(type default)
			)
			(layer "B.Fab")
		)
		(fp_line
			(start 0.12065 -0.305054)
			(end 0.12065 -0.2794)
			(stroke
				(width 0.1)
				(type default)
			)
			(layer "B.Fab")
		)
		(fp_line
			(start -0.12065 -0.3048)
			(end -0.67945 -0.3048)
			(stroke
				(width 0.1)
				(type default)
			)
			(layer "B.Fab")
		)
		(fp_line
			(start -0.67945 -0.3048)
			(end -0.67945 0.3048)
			(stroke
				(width 0.1)
				(type default)
			)
			(layer "B.Fab")
		)
		(fp_line
			(start 0.12065 -0.2794)
			(end -0.12065 -0.2794)
			(stroke
				(width 0.1)
				(type default)
			)
			(layer "B.Fab")
		)
		(fp_line
			(start -0.12065 -0.2794)
			(end -0.12065 -0.3048)
			(stroke
				(width 0.1)
				(type default)
			)
			(layer "B.Fab")
		)
		(fp_line
			(start 0.12065 0.2794)
			(end 0.12065 0.3048)
			(stroke
				(width 0.1)
				(type default)
			)
			(layer "B.Fab")
		)
		(fp_line
			(start -0.120396 0.2794)
			(end 0.12065 0.2794)
			(stroke
				(width 0.1)
				(type default)
			)
			(layer "B.Fab")
		)
		(fp_line
			(start 0.67945 0.3048)
			(end 0.67945 -0.305054)
			(stroke
				(width 0.1)
				(type default)
			)
			(layer "B.Fab")
		)
		(fp_line
			(start 0.12065 0.3048)
			(end 0.67945 0.3048)
			(stroke
				(width 0.1)
				(type default)
			)
			(layer "B.Fab")
		)
		(fp_line
			(start -0.120396 0.3048)
			(end -0.120396 0.2794)
			(stroke
				(width 0.1)
				(type default)
			)
			(layer "B.Fab")
		)
		(fp_line
			(start -0.67945 0.3048)
			(end -0.120396 0.3048)
			(stroke
				(width 0.1)
				(type default)
			)
			(layer "B.Fab")
		)
		(pad "1" smd circle
			(at 0.40005 0 270)
			(size 0 0)
			(layers "B.Cu" "B.Mask" "B.Paste")
			(net "PWRGD_CHH_CPU1_DIMM2")
		)
		(pad "2" smd circle
			(at -0.40005 0 270)
			(size 0 0)
			(layers "B.Cu" "B.Mask" "B.Paste")
			(net "PWRGD_FAIL_CPU1_GH")
		)
	)
	(footprint ""
		(layer "B.Cu")
		(at 209.295746 -77.263752)
		(property "Reference" "U222"
			(at 2.032 -3.27533 0)
			(unlocked yes)
			(layer "B.SilkS")
			(effects
				(font
					(size 0.7874 0.5842)
					(thickness 0.1524)
				)
				(justify left mirror)
			)
		)
		(property "Value" ""
			(at 0 0 0)
			(layer "B.Fab")
			(effects
				(font
					(size 1.27 1.27)
				)
				(justify mirror)
			)
		)
		(duplicate_pad_numbers_are_jumpers no)
		(fp_line
			(start -2.0066 -2.5527)
			(end -2.0066 2.5527)
			(stroke
				(width 0.1524)
				(type default)
			)
			(layer "B.SilkS")
		)
		(fp_line
			(start -2.0066 2.5527)
			(end 2.0066 2.5527)
			(stroke
				(width 0.1524)
				(type default)
			)
			(layer "B.SilkS")
		)
		(fp_line
			(start -0.5715 -2.5527)
			(end -2.0066 -2.5527)
			(stroke
				(width 0.1524)
				(type default)
			)
			(layer "B.SilkS")
		)
		(fp_line
			(start 0 -1.9812)
			(end -0.5715 -2.5527)
			(stroke
				(width 0.1524)
				(type default)
			)
			(layer "B.SilkS")
		)
		(fp_line
			(start 0.5715 -2.5527)
			(end 0 -1.9812)
			(stroke
				(width 0.1524)
				(type default)
			)
			(layer "B.SilkS")
		)
		(fp_line
			(start 2.0066 -2.5527)
			(end 0.5715 -2.5527)
			(stroke
				(width 0.1524)
				(type default)
			)
			(layer "B.SilkS")
		)
		(fp_line
			(start 2.0066 2.5527)
			(end 2.0066 -2.5527)
			(stroke
				(width 0.1524)
				(type default)
			)
			(layer "B.SilkS")
		)
		(fp_poly
			(pts
				(xy 4.36372 -1.608328) (xy 3.81 -1.905) (xy 4.36372 -2.233168)
			)
			(stroke
				(width 0)
				(type default)
			)
			(fill yes)
			(layer "B.SilkS")
		)
		(fp_line
			(start -2.249932 -2.549906)
			(end -2.249932 2.549906)
			(stroke
				(width 0.1)
				(type default)
			)
			(layer "B.Fab")
		)
		(fp_line
			(start -2.249932 2.549906)
			(end 2.249932 2.549906)
			(stroke
				(width 0.1)
				(type default)
			)
			(layer "B.Fab")
		)
		(fp_line
			(start 2.249932 -2.549906)
			(end -2.249932 -2.549906)
			(stroke
				(width 0.1)
				(type default)
			)
			(layer "B.Fab")
		)
		(fp_line
			(start 2.249932 2.549906)
			(end 2.249932 -2.549906)
			(stroke
				(width 0.1)
				(type default)
			)
			(layer "B.Fab")
		)
		(fp_poly
			(pts
				(xy 4.36372 -1.608328) (xy 4.36372 -2.233168) (xy 3.81 -1.905)
			)
			(stroke
				(width 0)
				(type default)
			)
			(fill yes)
			(layer "B.Fab")
		)
		(pad "1" smd rect
			(at 2.921 -1.949958 270)
			(size 0.3556 1.4986)
			(layers "B.Cu" "B.Mask" "B.Paste")
			(net "FB_BMC_ISOLATE1")
		)
		(pad "2" smd rect
			(at 2.921 -1.299972 270)
			(size 0.3556 1.4986)
			(layers "B.Cu" "B.Mask" "B.Paste")
			(net "NCSI_BMC_RXD1_R1")
		)
		(pad "3" smd rect
			(at 2.921 -0.649986 270)
			(size 0.3556 1.4986)
			(layers "B.Cu" "B.Mask" "B.Paste")
			(net "NCSI_OCP_V3_2_RXD1")
		)
		(pad "4" smd rect
			(at 2.921 0 270)
			(size 0.3556 1.4986)
			(layers "B.Cu" "B.Mask" "B.Paste")
			(net "FB_BMC_ISOLATE1")
		)
		(pad "5" smd rect
			(at 2.921 0.649986 270)
			(size 0.3556 1.4986)
			(layers "B.Cu" "B.Mask" "B.Paste")
			(net "NCSI_BMC_RXD0_R1")
		)
		(pad "6" smd rect
			(at 2.921 1.299972 270)
			(size 0.3556 1.4986)
			(layers "B.Cu" "B.Mask" "B.Paste")
			(net "NCSI_OCP_V3_2_RXD0")
		)
		(pad "7" smd rect
			(at 2.921 1.949958 270)
			(size 0.3556 1.4986)
			(layers "B.Cu" "B.Mask" "B.Paste")
			(net "GND")
		)
		(pad "8" smd rect
			(at -2.921 1.949958 270)
			(size 0.3556 1.4986)
			(layers "B.Cu" "B.Mask" "B.Paste")
			(net "NCSI_OCP_V3_2_CRS_DV")
		)
		(pad "9" smd rect
			(at -2.921 1.299972 270)
			(size 0.3556 1.4986)
			(layers "B.Cu" "B.Mask" "B.Paste")
			(net "NCSI_BMC_CRS_DV_R1")
		)
		(pad "10" smd rect
			(at -2.921 0.649986 270)
			(size 0.3556 1.4986)
			(layers "B.Cu" "B.Mask" "B.Paste")
			(net "FB_BMC_ISOLATE1")
		)
		(pad "11" smd rect
			(at -2.921 0 270)
			(size 0.3556 1.4986)
			(layers "B.Cu" "B.Mask" "B.Paste")
			(net "OCP_V3_2_ISO1_RBT_ARB_IN")
		)
		(pad "12" smd rect
			(at -2.921 -0.649986 270)
			(size 0.3556 1.4986)
			(layers "B.Cu" "B.Mask" "B.Paste")
			(net "OCP_V3_2_RBT_ARB_IN_R")
		)
		(pad "13" smd rect
			(at -2.921 -1.299972 270)
			(size 0.3556 1.4986)
			(layers "B.Cu" "B.Mask" "B.Paste")
			(net "FB_BMC_ISOLATE1")
		)
		(pad "14" smd rect
			(at -2.921 -1.949958 270)
			(size 0.3556 1.4986)
			(layers "B.Cu" "B.Mask" "B.Paste")
			(net "P3V3_AUX")
		)
	)
)
